(kicad_pcb
	(version 20260206)
	(generator "pcbnew")
	(generator_version "10.0")
	(general
		(thickness 1.6)
		(legacy_teardrops no)
	)
	(paper "A4")
	(title_block
		(title "peb — Lightning_PEB_BRD.brd")
		(comment 1 "Lightning (Wiwynn / Facebook NVMe JBOF) / footprints 1251-1257 of 2563")
	)
	(layers
		(0 "F.Cu" signal "TOP")
		(4 "In1.Cu" signal "L2GND")
		(6 "In2.Cu" signal "L3")
		(8 "In3.Cu" signal "L4VCC")
		(10 "In4.Cu" signal "L5VCC")
		(12 "In5.Cu" signal "L6")
		(14 "In6.Cu" signal "L7GND")
		(2 "B.Cu" signal "BOTTOM")
		(9 "F.Adhes" user "F.Adhesive")
		(11 "B.Adhes" user "B.Adhesive")
		(13 "F.Paste" user "Package Geometry/Pastemask Top")
		(15 "B.Paste" user "Package Geometry/Pastemask Bottom")
		(5 "F.SilkS" user "Ref Des/Silkscreen Top")
		(7 "B.SilkS" user "Ref Des/Silkscreen Bottom")
		(1 "F.Mask" user "Board Geometry/Soldermask Top")
		(3 "B.Mask" user "Board Geometry/Soldermask Bottom")
		(17 "Dwgs.User" user "User.Drawings")
		(19 "Cmts.User" user "User.Comments")
		(21 "Eco1.User" user "User.Eco1")
		(23 "Eco2.User" user "User.Eco2")
		(25 "Edge.Cuts" user "Board Geometry/Outline")
		(27 "Margin" user)
		(31 "F.CrtYd" user "Package Geometry/Place Bound Top")
		(29 "B.CrtYd" user "Package Geometry/Place Bound Bottom")
		(35 "F.Fab" user "Ref Des/Assembly Top")
		(33 "B.Fab" user "Ref Des/Assembly Bottom")
	)
	(footprint ""
		(layer "F.Cu")
		(at 21.5138 -83.82 180)
		(property "Reference" "C642"
			(at 0 0 180)
			(layer "F.SilkS")
			(hide yes)
			(effects
				(font
					(size 1.27 1.27)
				)
			)
		)
		(property "Value" "SCD22U10V2KX-1GP"
			(at 1.1811 -2.7051 180)
			(unlocked yes)
			(layer "F.Fab")
			(hide yes)
			(effects
				(font
					(size 1.016 1.016)
					(thickness 0.1524)
				)
			)
		)
		(property "Device Type" "C402H22"
			(at 1.1811 -4.2291 180)
			(unlocked yes)
			(layer "F.Fab")
			(hide yes)
			(effects
				(font
					(size 1.016 1.016)
					(thickness 0.1524)
				)
			)
		)
		(duplicate_pad_numbers_are_jumpers no)
		(fp_rect
			(start -0.4318 0.9525)
			(end 0.4318 -0.9525)
			(stroke
				(width 0)
				(type default)
			)
			(fill no)
			(layer "F.CrtYd")
		)
		(fp_rect
			(start -0.4318 0.9525)
			(end 0.4318 -0.9525)
			(stroke
				(width 0)
				(type default)
			)
			(fill no)
			(layer "F.Fab")
		)
		(pad "1" smd custom
			(at 0 -0.4445 180)
			(size 0.1524 0.1524)
			(layers "F.Cu" "F.Mask" "F.Paste")
			(net "PCIE_RX_CAP_N78")
			(options
				(clearance outline)
				(anchor circle)
			)
			(primitives
				(gr_poly
					(pts
						(arc
							(start 0.3048 -0.2032)
							(mid 0.275042 -0.275042)
							(end 0.2032 -0.3048)
						)
						(arc
							(start -0.2032 -0.3048)
							(mid -0.275042 -0.275042)
							(end -0.3048 -0.2032)
						)
						(arc
							(start -0.3048 0.2032)
							(mid -0.275042 0.275042)
							(end -0.2032 0.3048)
						)
						(arc
							(start 0.2032 0.3048)
							(mid 0.275042 0.275042)
							(end 0.3048 0.2032)
						)
					)
					(width 0)
					(fill yes)
				)
			)
		)
		(pad "2" smd custom
			(at 0 0.4445 180)
			(size 0.1524 0.1524)
			(layers "F.Cu" "F.Mask" "F.Paste")
			(net "PCIE_RX_N78")
			(options
				(clearance outline)
				(anchor circle)
			)
			(primitives
				(gr_poly
					(pts
						(arc
							(start 0.3048 -0.2032)
							(mid 0.275042 -0.275042)
							(end 0.2032 -0.3048)
						)
						(arc
							(start -0.2032 -0.3048)
							(mid -0.275042 -0.275042)
							(end -0.3048 -0.2032)
						)
						(arc
							(start -0.3048 0.2032)
							(mid -0.275042 0.275042)
							(end -0.2032 0.3048)
						)
						(arc
							(start 0.2032 0.3048)
							(mid 0.275042 0.275042)
							(end 0.3048 0.2032)
						)
					)
					(width 0)
					(fill yes)
				)
			)
		)
	)
	(footprint ""
		(layer "F.Cu")
		(at 33.032954 -165.137084 180)
		(property "Reference" "C172"
			(at 0 0 180)
			(layer "F.SilkS")
			(hide yes)
			(effects
				(font
					(size 1.27 1.27)
				)
			)
		)
		(property "Value" "SCD1U16V2KX-3GP"
			(at 1.1811 -2.7051 180)
			(unlocked yes)
			(layer "F.Fab")
			(hide yes)
			(effects
				(font
					(size 1.016 1.016)
					(thickness 0.1524)
				)
			)
		)
		(property "Device Type" "C402H22"
			(at 1.1811 -4.2291 180)
			(unlocked yes)
			(layer "F.Fab")
			(hide yes)
			(effects
				(font
					(size 1.016 1.016)
					(thickness 0.1524)
				)
			)
		)
		(duplicate_pad_numbers_are_jumpers no)
		(fp_rect
			(start -0.4318 0.9525)
			(end 0.4318 -0.9525)
			(stroke
				(width 0)
				(type default)
			)
			(fill no)
			(layer "F.CrtYd")
		)
		(fp_rect
			(start -0.4318 0.9525)
			(end 0.4318 -0.9525)
			(stroke
				(width 0)
				(type default)
			)
			(fill no)
			(layer "F.Fab")
		)
		(pad "1" smd custom
			(at 0 -0.4445 180)
			(size 0.1524 0.1524)
			(layers "F.Cu" "F.Mask" "F.Paste")
			(net "P1V53_STBY")
			(options
				(clearance outline)
				(anchor circle)
			)
			(primitives
				(gr_poly
					(pts
						(arc
							(start 0.3048 -0.2032)
							(mid 0.275042 -0.275042)
							(end 0.2032 -0.3048)
						)
						(arc
							(start -0.2032 -0.3048)
							(mid -0.275042 -0.275042)
							(end -0.3048 -0.2032)
						)
						(arc
							(start -0.3048 0.2032)
							(mid -0.275042 0.275042)
							(end -0.2032 0.3048)
						)
						(arc
							(start 0.2032 0.3048)
							(mid 0.275042 0.275042)
							(end 0.3048 0.2032)
						)
					)
					(width 0)
					(fill yes)
				)
			)
		)
		(pad "2" smd custom
			(at 0 0.4445 180)
			(size 0.1524 0.1524)
			(layers "F.Cu" "F.Mask" "F.Paste")
			(net "GND")
			(options
				(clearance outline)
				(anchor circle)
			)
			(primitives
				(gr_poly
					(pts
						(arc
							(start 0.3048 -0.2032)
							(mid 0.275042 -0.275042)
							(end 0.2032 -0.3048)
						)
						(arc
							(start -0.2032 -0.3048)
							(mid -0.275042 -0.275042)
							(end -0.3048 -0.2032)
						)
						(arc
							(start -0.3048 0.2032)
							(mid -0.275042 0.275042)
							(end -0.2032 0.3048)
						)
						(arc
							(start 0.2032 0.3048)
							(mid 0.275042 0.275042)
							(end 0.3048 0.2032)
						)
					)
					(width 0)
					(fill yes)
				)
			)
		)
	)
	(footprint ""
		(layer "F.Cu")
		(at 10.8966 -194.31 180)
		(property "Reference" "C7273"
			(at 0 0 180)
			(layer "F.SilkS")
			(hide yes)
			(effects
				(font
					(size 1.27 1.27)
				)
			)
		)
		(property "Value" "SCD01U16V2KX-3GP"
			(at 1.1811 -2.7051 180)
			(unlocked yes)
			(layer "F.Fab")
			(hide yes)
			(effects
				(font
					(size 1.016 1.016)
					(thickness 0.1524)
				)
			)
		)
		(property "Device Type" "C402H22"
			(at 1.1811 -4.2291 180)
			(unlocked yes)
			(layer "F.Fab")
			(hide yes)
			(effects
				(font
					(size 1.016 1.016)
					(thickness 0.1524)
				)
			)
		)
		(duplicate_pad_numbers_are_jumpers no)
		(fp_rect
			(start -0.4318 0.9525)
			(end 0.4318 -0.9525)
			(stroke
				(width 0)
				(type default)
			)
			(fill no)
			(layer "F.CrtYd")
		)
		(fp_rect
			(start -0.4318 0.9525)
			(end 0.4318 -0.9525)
			(stroke
				(width 0)
				(type default)
			)
			(fill no)
			(layer "F.Fab")
		)
		(pad "1" smd custom
			(at 0 -0.4445 180)
			(size 0.1524 0.1524)
			(layers "F.Cu" "F.Mask" "F.Paste")
			(net "MB0_TIME_R")
			(options
				(clearance outline)
				(anchor circle)
			)
			(primitives
				(gr_poly
					(pts
						(arc
							(start 0.3048 -0.2032)
							(mid 0.275042 -0.275042)
							(end 0.2032 -0.3048)
						)
						(arc
							(start -0.2032 -0.3048)
							(mid -0.275042 -0.275042)
							(end -0.3048 -0.2032)
						)
						(arc
							(start -0.3048 0.2032)
							(mid -0.275042 0.275042)
							(end -0.2032 0.3048)
						)
						(arc
							(start 0.2032 0.3048)
							(mid 0.275042 0.275042)
							(end 0.3048 0.2032)
						)
					)
					(width 0)
					(fill yes)
				)
			)
		)
		(pad "2" smd custom
			(at 0 0.4445 180)
			(size 0.1524 0.1524)
			(layers "F.Cu" "F.Mask" "F.Paste")
			(net "AGND_CURRENT_MON")
			(options
				(clearance outline)
				(anchor circle)
			)
			(primitives
				(gr_poly
					(pts
						(arc
							(start 0.3048 -0.2032)
							(mid 0.275042 -0.275042)
							(end 0.2032 -0.3048)
						)
						(arc
							(start -0.2032 -0.3048)
							(mid -0.275042 -0.275042)
							(end -0.3048 -0.2032)
						)
						(arc
							(start -0.3048 0.2032)
							(mid -0.275042 0.275042)
							(end -0.2032 0.3048)
						)
						(arc
							(start 0.2032 0.3048)
							(mid 0.275042 0.275042)
							(end 0.3048 0.2032)
						)
					)
					(width 0)
					(fill yes)
				)
			)
		)
	)
	(footprint ""
		(layer "F.Cu")
		(at 19.7612 -56.5404 180)
		(property "Reference" "R611"
			(at 0 0 180)
			(layer "F.SilkS")
			(hide yes)
			(effects
				(font
					(size 1.27 1.27)
				)
			)
		)
		(property "Value" "0R2J-2-GP"
			(at 0.064008 -3.993896 180)
			(unlocked yes)
			(layer "F.Fab")
			(hide yes)
			(effects
				(font
					(size 1.016 1.016)
					(thickness 0.1524)
				)
			)
		)
		(property "Device Type" "R402H16"
			(at 0.064008 -5.517896 180)
			(unlocked yes)
			(layer "F.Fab")
			(hide yes)
			(effects
				(font
					(size 1.016 1.016)
					(thickness 0.1524)
				)
			)
		)
		(duplicate_pad_numbers_are_jumpers no)
		(fp_line
			(start 0.508 -0.9398)
			(end -0.508 -0.9398)
			(stroke
				(width 0.1524)
				(type default)
			)
			(layer "F.SilkS")
		)
		(fp_line
			(start -0.508 -0.9398)
			(end -0.508 0.9398)
			(stroke
				(width 0.1524)
				(type default)
			)
			(layer "F.SilkS")
		)
		(fp_rect
			(start -0.508 0.9398)
			(end 0.508 -0.9398)
			(stroke
				(width 0)
				(type default)
			)
			(fill no)
			(layer "F.CrtYd")
		)
		(fp_rect
			(start -0.508 0.9398)
			(end 0.508 -0.9398)
			(stroke
				(width 0)
				(type default)
			)
			(fill no)
			(layer "F.Fab")
		)
		(pad "1" smd custom
			(at 0 -0.4445 180)
			(size 0.1397 0.1397)
			(layers "F.Cu" "F.Mask" "F.Paste")
			(net "NIC0_MDI0_N2")
			(options
				(clearance outline)
				(anchor circle)
			)
			(primitives
				(gr_poly
					(pts
						(arc
							(start -0.1778 -0.2794)
							(mid -0.249642 -0.249642)
							(end -0.2794 -0.1778)
						)
						(arc
							(start -0.2794 0.1778)
							(mid -0.249642 0.249642)
							(end -0.1778 0.2794)
						)
						(arc
							(start 0.1778 0.2794)
							(mid 0.249642 0.249642)
							(end 0.2794 0.1778)
						)
						(arc
							(start 0.2794 -0.1778)
							(mid 0.249642 -0.249642)
							(end 0.1778 -0.2794)
						)
					)
					(width 0)
					(fill yes)
				)
			)
		)
		(pad "2" smd custom
			(at 0 0.4445 180)
			(size 0.1397 0.1397)
			(layers "F.Cu" "F.Mask" "F.Paste")
			(net "MNG_TX_DN")
			(options
				(clearance outline)
				(anchor circle)
			)
			(primitives
				(gr_poly
					(pts
						(arc
							(start -0.1778 -0.2794)
							(mid -0.249642 -0.249642)
							(end -0.2794 -0.1778)
						)
						(arc
							(start -0.2794 0.1778)
							(mid -0.249642 0.249642)
							(end -0.1778 0.2794)
						)
						(arc
							(start 0.1778 0.2794)
							(mid 0.249642 0.249642)
							(end 0.2794 0.1778)
						)
						(arc
							(start 0.2794 -0.1778)
							(mid 0.249642 -0.249642)
							(end 0.1778 -0.2794)
						)
					)
					(width 0)
					(fill yes)
				)
			)
		)
	)
	(footprint ""
		(layer "F.Cu")
		(at 67.8942 -74.93 180)
		(property "Reference" "C186"
			(at 0 0 180)
			(layer "F.SilkS")
			(hide yes)
			(effects
				(font
					(size 1.27 1.27)
				)
			)
		)
		(property "Value" "SCD1U16V2KX-3GP"
			(at 1.1811 -2.7051 180)
			(unlocked yes)
			(layer "F.Fab")
			(hide yes)
			(effects
				(font
					(size 1.016 1.016)
					(thickness 0.1524)
				)
			)
		)
		(property "Device Type" "C402H22"
			(at 1.1811 -4.2291 180)
			(unlocked yes)
			(layer "F.Fab")
			(hide yes)
			(effects
				(font
					(size 1.016 1.016)
					(thickness 0.1524)
				)
			)
		)
		(duplicate_pad_numbers_are_jumpers no)
		(fp_rect
			(start -0.4318 0.9525)
			(end 0.4318 -0.9525)
			(stroke
				(width 0)
				(type default)
			)
			(fill no)
			(layer "F.CrtYd")
		)
		(fp_rect
			(start -0.4318 0.9525)
			(end 0.4318 -0.9525)
			(stroke
				(width 0)
				(type default)
			)
			(fill no)
			(layer "F.Fab")
		)
		(pad "1" smd custom
			(at 0 -0.4445 180)
			(size 0.1524 0.1524)
			(layers "F.Cu" "F.Mask" "F.Paste")
			(net "P3V3_STBY")
			(options
				(clearance outline)
				(anchor circle)
			)
			(primitives
				(gr_poly
					(pts
						(arc
							(start 0.3048 -0.2032)
							(mid 0.275042 -0.275042)
							(end 0.2032 -0.3048)
						)
						(arc
							(start -0.2032 -0.3048)
							(mid -0.275042 -0.275042)
							(end -0.3048 -0.2032)
						)
						(arc
							(start -0.3048 0.2032)
							(mid -0.275042 0.275042)
							(end -0.2032 0.3048)
						)
						(arc
							(start 0.2032 0.3048)
							(mid 0.275042 0.275042)
							(end 0.3048 0.2032)
						)
					)
					(width 0)
					(fill yes)
				)
			)
		)
		(pad "2" smd custom
			(at 0 0.4445 180)
			(size 0.1524 0.1524)
			(layers "F.Cu" "F.Mask" "F.Paste")
			(net "GND")
			(options
				(clearance outline)
				(anchor circle)
			)
			(primitives
				(gr_poly
					(pts
						(arc
							(start 0.3048 -0.2032)
							(mid 0.275042 -0.275042)
							(end 0.2032 -0.3048)
						)
						(arc
							(start -0.2032 -0.3048)
							(mid -0.275042 -0.275042)
							(end -0.3048 -0.2032)
						)
						(arc
							(start -0.3048 0.2032)
							(mid -0.275042 0.275042)
							(end -0.2032 0.3048)
						)
						(arc
							(start 0.2032 0.3048)
							(mid 0.275042 0.275042)
							(end 0.3048 0.2032)
						)
					)
					(width 0)
					(fill yes)
				)
			)
		)
	)
	(footprint ""
		(layer "F.Cu")
		(at 334.518 -69.723 -90)
		(property "Reference" "R610"
			(at 0 0 270)
			(layer "F.SilkS")
			(hide yes)
			(effects
				(font
					(size 1.27 1.27)
				)
			)
		)
		(property "Value" "4K7R2F-GP"
			(at 0.064008 -3.993896 270)
			(unlocked yes)
			(layer "F.Fab")
			(hide yes)
			(effects
				(font
					(size 1.016 1.016)
					(thickness 0.1524)
				)
			)
		)
		(property "Device Type" "R402H16"
			(at 0.064008 -5.517896 270)
			(unlocked yes)
			(layer "F.Fab")
			(hide yes)
			(effects
				(font
					(size 1.016 1.016)
					(thickness 0.1524)
				)
			)
		)
		(duplicate_pad_numbers_are_jumpers no)
		(fp_line
			(start -0.508 -0.9398)
			(end -0.508 0.9398)
			(stroke
				(width 0.1524)
				(type default)
			)
			(layer "F.SilkS")
		)
		(fp_line
			(start 0.508 -0.9398)
			(end -0.508 -0.9398)
			(stroke
				(width 0.1524)
				(type default)
			)
			(layer "F.SilkS")
		)
		(fp_rect
			(start -0.508 0.9398)
			(end 0.508 -0.9398)
			(stroke
				(width 0)
				(type default)
			)
			(fill no)
			(layer "F.CrtYd")
		)
		(fp_rect
			(start -0.508 0.9398)
			(end 0.508 -0.9398)
			(stroke
				(width 0)
				(type default)
			)
			(fill no)
			(layer "F.Fab")
		)
		(pad "1" smd custom
			(at 0 -0.4445 270)
			(size 0.1397 0.1397)
			(layers "F.Cu" "F.Mask" "F.Paste")
			(net "P0V9_E_PG")
			(options
				(clearance outline)
				(anchor circle)
			)
			(primitives
				(gr_poly
					(pts
						(arc
							(start -0.1778 -0.2794)
							(mid -0.249642 -0.249642)
							(end -0.2794 -0.1778)
						)
						(arc
							(start -0.2794 0.1778)
							(mid -0.249642 0.249642)
							(end -0.1778 0.2794)
						)
						(arc
							(start 0.1778 0.2794)
							(mid 0.249642 0.249642)
							(end 0.2794 0.1778)
						)
						(arc
							(start 0.2794 -0.1778)
							(mid 0.249642 -0.249642)
							(end 0.1778 -0.2794)
						)
					)
					(width 0)
					(fill yes)
				)
			)
		)
		(pad "2" smd custom
			(at 0 0.4445 270)
			(size 0.1397 0.1397)
			(layers "F.Cu" "F.Mask" "F.Paste")
			(net "P3V3_STBY")
			(options
				(clearance outline)
				(anchor circle)
			)
			(primitives
				(gr_poly
					(pts
						(arc
							(start -0.1778 -0.2794)
							(mid -0.249642 -0.249642)
							(end -0.2794 -0.1778)
						)
						(arc
							(start -0.2794 0.1778)
							(mid -0.249642 0.249642)
							(end -0.1778 0.2794)
						)
						(arc
							(start 0.1778 0.2794)
							(mid 0.249642 0.249642)
							(end 0.2794 0.1778)
						)
						(arc
							(start 0.2794 -0.1778)
							(mid 0.249642 -0.249642)
							(end 0.1778 -0.2794)
						)
					)
					(width 0)
					(fill yes)
				)
			)
		)
	)
	(footprint ""
		(layer "F.Cu")
		(at 53.721 -121.412 90)
		(property "Reference" "R336"
			(at 0 0 90)
			(layer "F.SilkS")
			(hide yes)
			(effects
				(font
					(size 1.27 1.27)
				)
			)
		)
		(property "Value" "0R2J-2-GP"
			(at 0.064008 -3.993896 90)
			(unlocked yes)
			(layer "F.Fab")
			(hide yes)
			(effects
				(font
					(size 1.016 1.016)
					(thickness 0.1524)
				)
			)
		)
		(property "Device Type" "R402H16"
			(at 0.064008 -5.517896 90)
			(unlocked yes)
			(layer "F.Fab")
			(hide yes)
			(effects
				(font
					(size 1.016 1.016)
					(thickness 0.1524)
				)
			)
		)
		(duplicate_pad_numbers_are_jumpers no)
		(fp_line
			(start 0.508 -0.9398)
			(end -0.508 -0.9398)
			(stroke
				(width 0.1524)
				(type default)
			)
			(layer "F.SilkS")
		)
		(fp_line
			(start -0.508 -0.9398)
			(end -0.508 0.9398)
			(stroke
				(width 0.1524)
				(type default)
			)
			(layer "F.SilkS")
		)
		(fp_rect
			(start -0.508 0.9398)
			(end 0.508 -0.9398)
			(stroke
				(width 0)
				(type default)
			)
			(fill no)
			(layer "F.CrtYd")
		)
		(fp_rect
			(start -0.508 0.9398)
			(end 0.508 -0.9398)
			(stroke
				(width 0)
				(type default)
			)
			(fill no)
			(layer "F.Fab")
		)
		(pad "1" smd custom
			(at 0 -0.4445 90)
			(size 0.1397 0.1397)
			(layers "F.Cu" "F.Mask" "F.Paste")
			(net "JTAG_BMC_TRST_N")
			(options
				(clearance outline)
				(anchor circle)
			)
			(primitives
				(gr_poly
					(pts
						(arc
							(start -0.1778 -0.2794)
							(mid -0.249642 -0.249642)
							(end -0.2794 -0.1778)
						)
						(arc
							(start -0.2794 0.1778)
							(mid -0.249642 0.249642)
							(end -0.1778 0.2794)
						)
						(arc
							(start 0.1778 0.2794)
							(mid 0.249642 0.249642)
							(end 0.2794 0.1778)
						)
						(arc
							(start 0.2794 -0.1778)
							(mid 0.249642 -0.249642)
							(end 0.1778 -0.2794)
						)
					)
					(width 0)
					(fill yes)
				)
			)
		)
		(pad "2" smd custom
			(at 0 0.4445 90)
			(size 0.1397 0.1397)
			(layers "F.Cu" "F.Mask" "F.Paste")
			(net "GND")
			(options
				(clearance outline)
				(anchor circle)
			)
			(primitives
				(gr_poly
					(pts
						(arc
							(start -0.1778 -0.2794)
							(mid -0.249642 -0.249642)
							(end -0.2794 -0.1778)
						)
						(arc
							(start -0.2794 0.1778)
							(mid -0.249642 0.249642)
							(end -0.1778 0.2794)
						)
						(arc
							(start 0.1778 0.2794)
							(mid 0.249642 0.249642)
							(end 0.2794 0.1778)
						)
						(arc
							(start 0.2794 -0.1778)
							(mid 0.249642 -0.249642)
							(end 0.1778 -0.2794)
						)
					)
					(width 0)
					(fill yes)
				)
			)
		)
	)
)
